(kicad_pcb
	(version 20241229)
	(generator "pcbnew")
	(generator_version "9.0")
	(general
		(thickness 1.711)
		(legacy_teardrops no)
	)
	(paper "A4")
	(title_block
		(title "Antmicro Baseboard for Jetson AGX Thor")
		(date "2026-02-18")
		(rev "1.1.0")
		(company "Antmicro Ltd")
		(comment 1 "www.antmicro.com")
		(comment 9 "footprints 56-60 of 1170")
	)
	(layers
		(0 "F.Cu" signal)
		(4 "In1.Cu" signal)
		(6 "In2.Cu" signal)
		(8 "In3.Cu" signal)
		(10 "In4.Cu" jumper)
		(12 "In5.Cu" signal)
		(14 "In6.Cu" signal)
		(16 "In7.Cu" signal)
		(18 "In8.Cu" signal)
		(2 "B.Cu" signal)
		(9 "F.Adhes" user "F.Adhesive")
		(11 "B.Adhes" user "B.Adhesive")
		(13 "F.Paste" user)
		(15 "B.Paste" user)
		(5 "F.SilkS" user "F.Silkscreen")
		(7 "B.SilkS" user "B.Silkscreen")
		(1 "F.Mask" user)
		(3 "B.Mask" user)
		(17 "Dwgs.User" user "User.Drawings")
		(19 "Cmts.User" user "User.Comments")
		(21 "Eco1.User" user "User.Eco1")
		(23 "Eco2.User" user "User.Eco2")
		(25 "Edge.Cuts" user)
		(27 "Margin" user)
		(31 "F.CrtYd" user "F.Courtyard")
		(29 "B.CrtYd" user "B.Courtyard")
		(35 "F.Fab" user)
		(33 "B.Fab" user)
	)
	(footprint "antmicro-footprints:C_0402_1005Metric"
		(layer "F.Cu")
		(at 211.2 78)
		(descr "Capacitor SMD 0402")
		(tags "capacitor SMD 0402")
		(property "Reference" "C234"
			(at 1 0.5 0)
			(layer "F.SilkS")
			(effects
				(font
					(size 0.7 0.7)
					(thickness 0.15)
				)
				(justify left bottom)
			)
		)
		(property "Value" "C_100n_0402"
			(at -1.022927 2.155213 0)
			(layer "F.Fab")
			(effects
				(font
					(size 0.7 0.7)
					(thickness 0.15)
				)
				(justify left bottom)
			)
		)
		(property "Datasheet" "https://www.murata.com/products/productdetail?partno=GRM155R61H104KE14%23"
			(at 0 0 0)
			(layer "F.Fab")
			(hide yes)
			(effects
				(font
					(size 1.27 1.27)
					(thickness 0.15)
				)
			)
		)
		(property "Description" "SMD Multilayer Ceramic Capacitor, 0.1 µF, 50 V, 0402 [1005 Metric], ± 10%, X5R, GRM Series"
			(at 0 0 0)
			(layer "F.Fab")
			(hide yes)
			(effects
				(font
					(size 1.27 1.27)
					(thickness 0.15)
				)
			)
		)
		(property "MPN" "GRM155R61H104KE14D"
			(at 0 0 0)
			(unlocked yes)
			(layer "F.Fab")
			(hide yes)
			(effects
				(font
					(size 1 1)
					(thickness 0.15)
				)
			)
		)
		(property "Manufacturer" "Murata"
			(at 0 0 0)
			(unlocked yes)
			(layer "F.Fab")
			(hide yes)
			(effects
				(font
					(size 1 1)
					(thickness 0.15)
				)
			)
		)
		(property "Val" "100n"
			(at 0 0 0)
			(unlocked yes)
			(layer "F.Fab")
			(hide yes)
			(effects
				(font
					(size 1 1)
					(thickness 0.15)
				)
			)
		)
		(property "License" "Apache-2.0"
			(at 0 0 0)
			(unlocked yes)
			(layer "F.Fab")
			(hide yes)
			(effects
				(font
					(size 1 1)
					(thickness 0.15)
				)
			)
		)
		(property "Author" "Antmicro"
			(at 0 0 0)
			(unlocked yes)
			(layer "F.Fab")
			(hide yes)
			(effects
				(font
					(size 1 1)
					(thickness 0.15)
				)
			)
		)
		(property "Voltage" "50V"
			(at 0 0 0)
			(unlocked yes)
			(layer "F.Fab")
			(hide yes)
			(effects
				(font
					(size 1 1)
					(thickness 0.15)
				)
			)
		)
		(property "Dielectric" "X5R"
			(at 0 0 0)
			(unlocked yes)
			(layer "F.Fab")
			(hide yes)
			(effects
				(font
					(size 1 1)
					(thickness 0.15)
				)
			)
		)
		(sheetname "/USB Debug, PD/")
		(sheetfile "usb_debug_pd.kicad_sch")
		(attr smd)
		(fp_poly
			(pts
				(xy -0.925 -0.47) (xy -0.925 0.47) (xy 0.925 0.47) (xy 0.925 -0.47)
			)
			(stroke
				(width 0.05)
				(type default)
			)
			(fill no)
			(layer "F.CrtYd")
		)
		(fp_line
			(start -0.494 -0.25)
			(end 0.504 -0.25)
			(stroke
				(width 0.15)
				(type solid)
			)
			(layer "F.Fab")
		)
		(fp_line
			(start -0.494 0.248)
			(end -0.494 -0.25)
			(stroke
				(width 0.15)
				(type solid)
			)
			(layer "F.Fab")
		)
		(fp_line
			(start 0.504 -0.25)
			(end 0.504 0.248)
			(stroke
				(width 0.15)
				(type solid)
			)
			(layer "F.Fab")
		)
		(fp_line
			(start 0.504 0.248)
			(end -0.494 0.248)
			(stroke
				(width 0.15)
				(type solid)
			)
			(layer "F.Fab")
		)
		(fp_text user "${REFERENCE}"
			(at -0.939 4.599 0)
			(layer "F.Fab")
			(effects
				(font
					(size 0.7 0.7)
					(thickness 0.15)
				)
				(justify left bottom)
			)
		)
		(fp_text user "Author: Antmicro"
			(at -0.939 3.399 0)
			(layer "F.Fab")
			(effects
				(font
					(size 0.7 0.7)
					(thickness 0.15)
				)
				(justify left bottom)
			)
		)
		(fp_text user "License: Apache-2.0"
			(at -0.939 5.799 0)
			(layer "F.Fab")
			(effects
				(font
					(size 0.7 0.7)
					(thickness 0.15)
				)
				(justify left bottom)
			)
		)
		(pad "1" smd roundrect
			(at -0.48 0)
			(size 0.59 0.64)
			(layers "F.Cu" "F.Mask" "F.Paste")
			(roundrect_rratio 0.25)
			(net 334 "/USB Debug, PD/FTDI_3V3")
			(pintype "passive")
		)
		(pad "2" smd roundrect
			(at 0.48 0)
			(size 0.59 0.64)
			(layers "F.Cu" "F.Mask" "F.Paste")
			(roundrect_rratio 0.25)
			(net 1 "GND")
			(pintype "passive")
		)
	)
	(footprint "antmicro-footprints:C_0402_1005Metric"
		(layer "F.Cu")
		(at 178.2 87.42)
		(descr "Capacitor SMD 0402")
		(tags "capacitor SMD 0402")
		(property "Reference" "C246"
			(at -1.765532 -1.325 0)
			(layer "F.SilkS")
			(effects
				(font
					(size 0.7 0.7)
					(thickness 0.15)
				)
				(justify left bottom)
			)
		)
		(property "Value" "C_100n_0402"
			(at -1.022927 2.155213 0)
			(layer "F.Fab")
			(effects
				(font
					(size 0.7 0.7)
					(thickness 0.15)
				)
				(justify left bottom)
			)
		)
		(property "Datasheet" "https://www.murata.com/products/productdetail?partno=GRM155R61H104KE14%23"
			(at 0 0 0)
			(layer "F.Fab")
			(hide yes)
			(effects
				(font
					(size 1.27 1.27)
					(thickness 0.15)
				)
			)
		)
		(property "Description" "SMD Multilayer Ceramic Capacitor, 0.1 µF, 50 V, 0402 [1005 Metric], ± 10%, X5R, GRM Series"
			(at 0 0 0)
			(layer "F.Fab")
			(hide yes)
			(effects
				(font
					(size 1.27 1.27)
					(thickness 0.15)
				)
			)
		)
		(property "Manufacturer" "Murata"
			(at 0 0 0)
			(unlocked yes)
			(layer "F.Fab")
			(hide yes)
			(effects
				(font
					(size 1 1)
					(thickness 0.15)
				)
			)
		)
		(property "MPN" "GRM155R61H104KE14D"
			(at 0 0 0)
			(unlocked yes)
			(layer "F.Fab")
			(hide yes)
			(effects
				(font
					(size 1 1)
					(thickness 0.15)
				)
			)
		)
		(property "Val" "100n"
			(at 0 0 0)
			(unlocked yes)
			(layer "F.Fab")
			(hide yes)
			(effects
				(font
					(size 1 1)
					(thickness 0.15)
				)
			)
		)
		(property "License" "Apache-2.0"
			(at 0 0 0)
			(unlocked yes)
			(layer "F.Fab")
			(hide yes)
			(effects
				(font
					(size 1 1)
					(thickness 0.15)
				)
			)
		)
		(property "Author" "Antmicro"
			(at 0 0 0)
			(unlocked yes)
			(layer "F.Fab")
			(hide yes)
			(effects
				(font
					(size 1 1)
					(thickness 0.15)
				)
			)
		)
		(property "Voltage" "50V"
			(at 0 0 0)
			(unlocked yes)
			(layer "F.Fab")
			(hide yes)
			(effects
				(font
					(size 1 1)
					(thickness 0.15)
				)
			)
		)
		(property "Dielectric" "X5R"
			(at 0 0 0)
			(unlocked yes)
			(layer "F.Fab")
			(hide yes)
			(effects
				(font
					(size 1 1)
					(thickness 0.15)
				)
			)
		)
		(component_classes
			(class "DCDC_SOM")
		)
		(sheetname "/DCDC/")
		(sheetfile "dcdc.kicad_sch")
		(attr smd)
		(fp_rect
			(start -0.925 -0.47)
			(end 0.925 0.47)
			(stroke
				(width 0.05)
				(type default)
			)
			(fill no)
			(layer "F.CrtYd")
		)
		(fp_line
			(start -0.494 -0.25)
			(end 0.504 -0.25)
			(stroke
				(width 0.15)
				(type solid)
			)
			(layer "F.Fab")
		)
		(fp_line
			(start -0.494 0.248)
			(end -0.494 -0.25)
			(stroke
				(width 0.15)
				(type solid)
			)
			(layer "F.Fab")
		)
		(fp_line
			(start 0.504 -0.25)
			(end 0.504 0.248)
			(stroke
				(width 0.15)
				(type solid)
			)
			(layer "F.Fab")
		)
		(fp_line
			(start 0.504 0.248)
			(end -0.494 0.248)
			(stroke
				(width 0.15)
				(type solid)
			)
			(layer "F.Fab")
		)
		(fp_text user "${REFERENCE}"
			(at -0.939 4.599 0)
			(layer "F.Fab")
			(effects
				(font
					(size 0.7 0.7)
					(thickness 0.15)
				)
				(justify left bottom)
			)
		)
		(fp_text user "License: Apache-2.0"
			(at -0.939 5.799 0)
			(layer "F.Fab")
			(effects
				(font
					(size 0.7 0.7)
					(thickness 0.15)
				)
				(justify left bottom)
			)
		)
		(fp_text user "Author: Antmicro"
			(at -0.939 3.399 0)
			(layer "F.Fab")
			(effects
				(font
					(size 0.7 0.7)
					(thickness 0.15)
				)
				(justify left bottom)
			)
		)
		(pad "1" smd roundrect
			(at -0.48 0)
			(size 0.59 0.64)
			(layers "F.Cu" "F.Mask" "F.Paste")
			(roundrect_rratio 0.25)
			(net 902 "/DCDC/16V_PHASE")
			(pintype "passive")
		)
		(pad "2" smd roundrect
			(at 0.48 0)
			(size 0.59 0.64)
			(layers "F.Cu" "F.Mask" "F.Paste")
			(roundrect_rratio 0.25)
			(net 901 "/DCDC/16V_BOOT")
			(pintype "passive")
		)
	)
	(footprint "antmicro-footprints:R_0402_1005Metric"
		(layer "F.Cu")
		(at 168.81 63.49 90)
		(descr "Resistor SMD 0402")
		(tags "resistor SMD 0402")
		(property "Reference" "R231"
			(at -1.01 -1.61 90)
			(layer "F.SilkS")
			(effects
				(font
					(size 0.7 0.7)
					(thickness 0.15)
				)
				(justify left bottom)
			)
		)
		(property "Value" "R_200R_0402"
			(at -1.011843 1.772047 90)
			(layer "F.Fab")
			(effects
				(font
					(size 0.7 0.7)
					(thickness 0.15)
				)
				(justify left bottom)
			)
		)
		(property "Datasheet" "https://www.bourns.com/docs/product-datasheets/cr.pdf"
			(at 0 0 90)
			(layer "F.Fab")
			(hide yes)
			(effects
				(font
					(size 1.27 1.27)
					(thickness 0.15)
				)
			)
		)
		(property "Description" "SMD Chip Resistor, 200 ohm, ± 1%, 62.5 mW, 0402 [1005 Metric], Thick Film, General Purpose"
			(at 0 0 90)
			(layer "F.Fab")
			(hide yes)
			(effects
				(font
					(size 1.27 1.27)
					(thickness 0.15)
				)
			)
		)
		(property "Manufacturer" "Bourns"
			(at 0 0 90)
			(unlocked yes)
			(layer "F.Fab")
			(hide yes)
			(effects
				(font
					(size 1 1)
					(thickness 0.15)
				)
			)
		)
		(property "MPN" "CR0402-FX-2000GLF"
			(at 0 0 90)
			(unlocked yes)
			(layer "F.Fab")
			(hide yes)
			(effects
				(font
					(size 1 1)
					(thickness 0.15)
				)
			)
		)
		(property "Val" "200R"
			(at 0 0 90)
			(unlocked yes)
			(layer "F.Fab")
			(hide yes)
			(effects
				(font
					(size 1 1)
					(thickness 0.15)
				)
			)
		)
		(property "License" "Apache-2.0"
			(at 0 0 90)
			(unlocked yes)
			(layer "F.Fab")
			(hide yes)
			(effects
				(font
					(size 1 1)
					(thickness 0.15)
				)
			)
		)
		(property "Author" "Antmicro"
			(at 0 0 90)
			(unlocked yes)
			(layer "F.Fab")
			(hide yes)
			(effects
				(font
					(size 1 1)
					(thickness 0.15)
				)
			)
		)
		(property "Tolerance" "1%"
			(at 0 0 90)
			(unlocked yes)
			(layer "F.Fab")
			(hide yes)
			(effects
				(font
					(size 1 1)
					(thickness 0.15)
				)
			)
		)
		(sheetname "/Peripherals/")
		(sheetfile "peripherals.kicad_sch")
		(attr smd)
		(fp_rect
			(start -0.925 -0.47)
			(end 0.925 0.47)
			(stroke
				(width 0.05)
				(type default)
			)
			(fill no)
			(layer "F.CrtYd")
		)
		(fp_rect
			(start -0.5 -0.25)
			(end 0.5 0.25)
			(stroke
				(width 0.15)
				(type solid)
			)
			(fill no)
			(layer "F.Fab")
		)
		(fp_text user "License: Apache-2.0"
			(at -0.95 5.169 90)
			(layer "F.Fab")
			(effects
				(font
					(size 0.7 0.7)
					(thickness 0.15)
				)
				(justify left bottom)
			)
		)
		(fp_text user "${REFERENCE}"
			(at -0.95 3.168 90)
			(layer "F.Fab")
			(effects
				(font
					(size 0.7 0.7)
					(thickness 0.15)
				)
				(justify left bottom)
			)
		)
		(fp_text user "Author: Antmicro"
			(at -0.95 4.169 90)
			(layer "F.Fab")
			(effects
				(font
					(size 0.7 0.7)
					(thickness 0.15)
				)
				(justify left bottom)
			)
		)
		(pad "1" smd roundrect
			(at -0.48 0 90)
			(size 0.59 0.64)
			(layers "F.Cu" "F.Mask" "F.Paste")
			(roundrect_rratio 0.25)
			(net 36 "Net-(D35-A)")
			(pintype "passive")
		)
		(pad "2" smd roundrect
			(at 0.48 0 90)
			(size 0.59 0.64)
			(layers "F.Cu" "F.Mask" "F.Paste")
			(roundrect_rratio 0.25)
			(net 2 "+3V3")
			(pintype "passive")
		)
	)
	(footprint "antmicro-footprints:R_0402_1005Metric"
		(layer "F.Cu")
		(at 195.1 129.3 180)
		(descr "Resistor SMD 0402")
		(tags "resistor SMD 0402")
		(property "Reference" "R90"
			(at -1.1 -4.6 0)
			(layer "F.SilkS")
			(effects
				(font
					(size 0.7 0.7)
					(thickness 0.15)
				)
				(justify right top)
			)
		)
		(property "Value" "R_0R_0402"
			(at -1.011843 1.772047 0)
			(layer "F.Fab")
			(effects
				(font
					(size 0.7 0.7)
					(thickness 0.15)
				)
				(justify right top)
			)
		)
		(property "Datasheet" "https://industrial.panasonic.com/cdbs/www-data/pdf/RDA0000/AOA0000C301.pdf"
			(at 0 0 0)
			(layer "F.Fab")
			(hide yes)
			(effects
				(font
					(size 1.27 1.27)
					(thickness 0.15)
				)
			)
		)
		(property "Description" "SMD Chip Resistor, Jumper, 0 ohm, 100 mW, 0402 [1005 Metric], Thick Film, General Purpose"
			(at 0 0 0)
			(layer "F.Fab")
			(hide yes)
			(effects
				(font
					(size 1.27 1.27)
					(thickness 0.15)
				)
			)
		)
		(property "Manufacturer" "Panasonic"
			(at 0 0 180)
			(unlocked yes)
			(layer "F.Fab")
			(hide yes)
			(effects
				(font
					(size 1 1)
					(thickness 0.15)
				)
			)
		)
		(property "MPN" "ERJ2GE0R00X"
			(at 0 0 180)
			(unlocked yes)
			(layer "F.Fab")
			(hide yes)
			(effects
				(font
					(size 1 1)
					(thickness 0.15)
				)
			)
		)
		(property "Val" "0R"
			(at 0 0 180)
			(unlocked yes)
			(layer "F.Fab")
			(hide yes)
			(effects
				(font
					(size 1 1)
					(thickness 0.15)
				)
			)
		)
		(property "License" "Apache-2.0"
			(at 0 0 180)
			(unlocked yes)
			(layer "F.Fab")
			(hide yes)
			(effects
				(font
					(size 1 1)
					(thickness 0.15)
				)
			)
		)
		(property "Author" "Antmicro"
			(at 0 0 180)
			(unlocked yes)
			(layer "F.Fab")
			(hide yes)
			(effects
				(font
					(size 1 1)
					(thickness 0.15)
				)
			)
		)
		(property "Tolerance" "~"
			(at 0 0 180)
			(unlocked yes)
			(layer "F.Fab")
			(hide yes)
			(effects
				(font
					(size 1 1)
					(thickness 0.15)
				)
			)
		)
		(property "Current" "1A"
			(at 0 0 180)
			(unlocked yes)
			(layer "F.Fab")
			(hide yes)
			(effects
				(font
					(size 1 1)
					(thickness 0.15)
				)
			)
		)
		(sheetname "/USB Hub/")
		(sheetfile "usb_hub.kicad_sch")
		(attr smd exclude_from_pos_files exclude_from_bom dnp)
		(fp_rect
			(start -0.925 -0.47)
			(end 0.925 0.47)
			(stroke
				(width 0.05)
				(type default)
			)
			(fill no)
			(layer "F.CrtYd")
		)
		(fp_rect
			(start -0.5 -0.25)
			(end 0.5 0.25)
			(stroke
				(width 0.15)
				(type solid)
			)
			(fill no)
			(layer "F.Fab")
		)
		(fp_text user "${REFERENCE}"
			(at -0.95 3.168 0)
			(layer "F.Fab")
			(effects
				(font
					(size 0.7 0.7)
					(thickness 0.15)
				)
				(justify right top)
			)
		)
		(fp_text user "License: Apache-2.0"
			(at -0.95 5.169 0)
			(layer "F.Fab")
			(effects
				(font
					(size 0.7 0.7)
					(thickness 0.15)
				)
				(justify right top)
			)
		)
		(fp_text user "Author: Antmicro"
			(at -0.95 4.169 0)
			(layer "F.Fab")
			(effects
				(font
					(size 0.7 0.7)
					(thickness 0.15)
				)
				(justify right top)
			)
		)
		(pad "1" smd roundrect
			(at -0.48 0 180)
			(size 0.59 0.64)
			(layers "F.Cu" "F.Mask" "F.Paste")
			(roundrect_rratio 0.25)
			(net 930 "/USB Hub/HUB_SPI_CE_N")
			(pintype "passive")
		)
		(pad "2" smd roundrect
			(at 0.48 0 180)
			(size 0.59 0.64)
			(layers "F.Cu" "F.Mask" "F.Paste")
			(roundrect_rratio 0.25)
			(net 929 "/USB Debug, PD/SPI_{HUB_DEBUG}.~{CS0}")
			(pintype "passive")
		)
	)
	(footprint "antmicro-footprints:C_0805_2012Metric"
		(layer "F.Cu")
		(at 169.52 69.1 90)
		(descr "Capacitor SMD 0805")
		(tags "capacitor SMD 0805")
		(property "Reference" "C274"
			(at -1.41 -1.960532 90)
			(layer "F.SilkS")
			(effects
				(font
					(size 0.7 0.7)
					(thickness 0.15)
				)
				(justify left bottom)
			)
		)
		(property "Value" "C_22u_25V_0805"
			(at -2.055717 1.963152 90)
			(layer "F.Fab")
			(effects
				(font
					(size 0.7 0.7)
					(thickness 0.15)
				)
				(justify left bottom)
			)
		)
		(property "Datasheet" "https://product.samsungsem.com/mlcc/CL21A226MAYNNN.do"
			(at 0 0 90)
			(layer "F.Fab")
			(hide yes)
			(effects
				(font
					(size 1.27 1.27)
					(thickness 0.15)
				)
			)
		)
		(property "Description" "SMT Multilayer Ceramic Capacitor, 22uF, +/-20%, 25V, X5R, 0805 [2012 Metric]"
			(at 0 0 90)
			(layer "F.Fab")
			(hide yes)
			(effects
				(font
					(size 1.27 1.27)
					(thickness 0.15)
				)
			)
		)
		(property "MPN" "CL21A226MAYNNNE"
			(at 0 0 90)
			(unlocked yes)
			(layer "F.Fab")
			(hide yes)
			(effects
				(font
					(size 1 1)
					(thickness 0.15)
				)
			)
		)
		(property "Manufacturer" "Samsung Electro-Mechanics"
			(at 0 0 90)
			(unlocked yes)
			(layer "F.Fab")
			(hide yes)
			(effects
				(font
					(size 1 1)
					(thickness 0.15)
				)
			)
		)
		(property "License" "Apache-2.0"
			(at 0 0 90)
			(unlocked yes)
			(layer "F.Fab")
			(hide yes)
			(effects
				(font
					(size 1 1)
					(thickness 0.15)
				)
			)
		)
		(property "Author" "Antmicro"
			(at 0 0 90)
			(unlocked yes)
			(layer "F.Fab")
			(hide yes)
			(effects
				(font
					(size 1 1)
					(thickness 0.15)
				)
			)
		)
		(property "Val" "22u"
			(at 0 0 90)
			(unlocked yes)
			(layer "F.Fab")
			(hide yes)
			(effects
				(font
					(size 1 1)
					(thickness 0.15)
				)
			)
		)
		(property "Voltage" "25V"
			(at 0 0 90)
			(unlocked yes)
			(layer "F.Fab")
			(hide yes)
			(effects
				(font
					(size 1 1)
					(thickness 0.15)
				)
			)
		)
		(property "Dielectric" "X5R"
			(at 0 0 90)
			(unlocked yes)
			(layer "F.Fab")
			(hide yes)
			(effects
				(font
					(size 1 1)
					(thickness 0.15)
				)
			)
		)
		(property "Public" "False"
			(at 0 0 90)
			(unlocked yes)
			(layer "F.Fab")
			(hide yes)
			(effects
				(font
					(size 1 1)
					(thickness 0.15)
				)
			)
		)
		(component_classes
			(class "DCDC_20V")
		)
		(sheetname "/DCDC/")
		(sheetfile "dcdc.kicad_sch")
		(attr smd)
		(fp_line
			(start -0.3 -0.7)
			(end 0.3 -0.7)
			(stroke
				(width 0.15)
				(type solid)
			)
			(layer "F.SilkS")
		)
		(fp_line
			(start -0.3 0.7)
			(end 0.3 0.7)
			(stroke
				(width 0.15)
				(type solid)
			)
			(layer "F.SilkS")
		)
		(fp_rect
			(start 1.95 -0.9)
			(end -1.95 0.9)
			(stroke
				(width 0.05)
				(type default)
			)
			(fill no)
			(layer "F.CrtYd")
		)
		(fp_rect
			(start -0.95 -0.675)
			(end 0.95 0.675)
			(stroke
				(width 0.15)
				(type solid)
			)
			(fill no)
			(layer "F.Fab")
		)
		(fp_text user "License: Apache-2.0"
			(at -1.9 4.947 90)
			(layer "F.Fab")
			(effects
				(font
					(size 0.7 0.7)
					(thickness 0.15)
				)
				(justify left bottom)
			)
		)
		(fp_text user "${REFERENCE}"
			(at -1.9 3.947 90)
			(layer "F.Fab")
			(effects
				(font
					(size 0.7 0.7)
					(thickness 0.15)
				)
				(justify left bottom)
			)
		)
		(fp_text user "Author: Antmicro"
			(at -1.9 5.947 90)
			(layer "F.Fab")
			(effects
				(font
					(size 0.7 0.7)
					(thickness 0.15)
				)
				(justify left bottom)
			)
		)
		(pad "1" smd roundrect
			(at -1.1 0 90)
			(size 1.2 1.3)
			(layers "F.Cu" "F.Mask" "F.Paste")
			(roundrect_rratio 0.25)
			(net 1 "GND")
			(pintype "passive")
		)
		(pad "2" smd roundrect
			(at 1.1 0 90)
			(size 1.2 1.3)
			(layers "F.Cu" "F.Mask" "F.Paste")
			(roundrect_rratio 0.25)
			(net 13 "VCC")
			(pintype "passive")
		)
	)
)
